(kicad_pcb
	(version 20260206)
	(generator "pcbnew")
	(generator_version "10.0")
	(general
		(thickness 1.6)
		(legacy_teardrops no)
	)
	(paper "A4")
	(title_block
		(title "03242023_DA0F0TMBIJ0_F0T_Motherboard_J_brd_V01_OCP.brd")
		(comment 1 "Grand Teton / footprints 3767-3773 of 6105")
	)
	(layers
		(0 "F.Cu" signal "TOP")
		(4 "In1.Cu" signal "GND")
		(6 "In2.Cu" signal "IN1")
		(8 "In3.Cu" signal "GND1")
		(10 "In4.Cu" signal "IN2")
		(12 "In5.Cu" signal "GND2")
		(14 "In6.Cu" signal "IN3")
		(16 "In7.Cu" signal "GND3")
		(18 "In8.Cu" signal "VCC")
		(20 "In9.Cu" signal "VCC1")
		(22 "In10.Cu" signal "GND4")
		(24 "In11.Cu" signal "IN4")
		(26 "In12.Cu" signal "GND5")
		(28 "In13.Cu" signal "IN5")
		(30 "In14.Cu" signal "GND6")
		(32 "In15.Cu" signal "IN6")
		(34 "In16.Cu" signal "GND7")
		(2 "B.Cu" signal "BOTTOM")
		(9 "F.Adhes" user "F.Adhesive")
		(11 "B.Adhes" user "B.Adhesive")
		(13 "F.Paste" user "Package Geometry/Pastemask Top")
		(15 "B.Paste" user "Package Geometry/Pastemask Bottom")
		(5 "F.SilkS" user "Ref Des/Silkscreen Top")
		(7 "B.SilkS" user "Ref Des/Silkscreen Bottom")
		(1 "F.Mask" user "Board Geometry/Soldermask Top")
		(3 "B.Mask" user "Board Geometry/Soldermask Bottom")
		(17 "Dwgs.User" user "User.Drawings")
		(19 "Cmts.User" user "User.Comments")
		(21 "Eco1.User" user "User.Eco1")
		(23 "Eco2.User" user "User.Eco2")
		(25 "Edge.Cuts" user "Board Geometry/Outline")
		(27 "Margin" user)
		(31 "F.CrtYd" user "Package Geometry/Place Bound Top")
		(29 "B.CrtYd" user "Package Geometry/Place Bound Bottom")
		(35 "F.Fab" user "Ref Des/Assembly Top")
		(33 "B.Fab" user "Ref Des/Assembly Bottom")
	)
	(footprint ""
		(layer "F.Cu")
		(at 419.76294 -101.270308 90)
		(property "Reference" "PR3846"
			(at 0 0 90)
			(layer "F.SilkS")
			(hide yes)
			(effects
				(font
					(size 1.27 1.27)
				)
			)
		)
		(property "Value" ""
			(at 0 0 90)
			(layer "F.Fab")
			(effects
				(font
					(size 1.27 1.27)
				)
			)
		)
		(duplicate_pad_numbers_are_jumpers no)
		(fp_line
			(start 0.7874 -0.4064)
			(end 0.7874 0.4064)
			(stroke
				(width 0.1524)
				(type default)
			)
			(layer "F.SilkS")
		)
		(fp_line
			(start -0.7874 -0.4064)
			(end 0.7874 -0.4064)
			(stroke
				(width 0.1524)
				(type default)
			)
			(layer "F.SilkS")
		)
		(fp_line
			(start 0.7874 0.4064)
			(end -0.7874 0.4064)
			(stroke
				(width 0.1524)
				(type default)
			)
			(layer "F.SilkS")
		)
		(fp_line
			(start -0.7874 0.4064)
			(end -0.7874 -0.4064)
			(stroke
				(width 0.1524)
				(type default)
			)
			(layer "F.SilkS")
		)
		(fp_line
			(start -0.12065 -0.305054)
			(end -0.12065 -0.2794)
			(stroke
				(width 0.1)
				(type default)
			)
			(layer "F.Fab")
		)
		(fp_line
			(start -0.67945 -0.305054)
			(end -0.12065 -0.305054)
			(stroke
				(width 0.1)
				(type default)
			)
			(layer "F.Fab")
		)
		(fp_line
			(start 0.67945 -0.3048)
			(end 0.67945 0.3048)
			(stroke
				(width 0.1)
				(type default)
			)
			(layer "F.Fab")
		)
		(fp_line
			(start 0.12065 -0.3048)
			(end 0.67945 -0.3048)
			(stroke
				(width 0.1)
				(type default)
			)
			(layer "F.Fab")
		)
		(fp_line
			(start 0.12065 -0.2794)
			(end 0.12065 -0.3048)
			(stroke
				(width 0.1)
				(type default)
			)
			(layer "F.Fab")
		)
		(fp_line
			(start -0.12065 -0.2794)
			(end 0.12065 -0.2794)
			(stroke
				(width 0.1)
				(type default)
			)
			(layer "F.Fab")
		)
		(fp_line
			(start 0.120396 0.2794)
			(end -0.12065 0.2794)
			(stroke
				(width 0.1)
				(type default)
			)
			(layer "F.Fab")
		)
		(fp_line
			(start -0.12065 0.2794)
			(end -0.12065 0.3048)
			(stroke
				(width 0.1)
				(type default)
			)
			(layer "F.Fab")
		)
		(fp_line
			(start 0.67945 0.3048)
			(end 0.120396 0.3048)
			(stroke
				(width 0.1)
				(type default)
			)
			(layer "F.Fab")
		)
		(fp_line
			(start 0.120396 0.3048)
			(end 0.120396 0.2794)
			(stroke
				(width 0.1)
				(type default)
			)
			(layer "F.Fab")
		)
		(fp_line
			(start -0.12065 0.3048)
			(end -0.67945 0.3048)
			(stroke
				(width 0.1)
				(type default)
			)
			(layer "F.Fab")
		)
		(fp_line
			(start -0.67945 0.3048)
			(end -0.67945 -0.305054)
			(stroke
				(width 0.1)
				(type default)
			)
			(layer "F.Fab")
		)
		(pad "1" smd circle
			(at -0.40005 0 90)
			(size 0 0)
			(layers "F.Cu" "F.Mask" "F.Paste")
			(net "GND")
		)
		(pad "2" smd circle
			(at 0.40005 0 90)
			(size 0 0)
			(layers "F.Cu" "F.Mask" "F.Paste")
			(net "P3V3_OCP_ILIMIT_1")
		)
	)
	(footprint ""
		(layer "F.Cu")
		(at 193.954654 -153.774902)
		(property "Reference" "H124"
			(at 1.36144 6.74243 0)
			(unlocked yes)
			(layer "F.SilkS")
			(effects
				(font
					(size 0.7874 0.5842)
					(thickness 0.1524)
				)
				(justify left)
			)
		)
		(property "Value" ""
			(at 0 0 0)
			(layer "F.Fab")
			(effects
				(font
					(size 1.27 1.27)
				)
			)
		)
		(duplicate_pad_numbers_are_jumpers no)
		(fp_circle
			(center 0 0)
			(end 5.8166 0)
			(stroke
				(width 0.1524)
				(type default)
			)
			(fill no)
			(layer "F.SilkS")
		)
		(fp_circle
			(center 0 0)
			(end 5.8166 0)
			(stroke
				(width 0.1524)
				(type default)
			)
			(fill no)
			(layer "B.SilkS")
		)
		(fp_circle
			(center 0 0)
			(end 5.8166 0)
			(stroke
				(width 0.1)
				(type default)
			)
			(fill no)
			(layer "B.Fab")
		)
		(fp_circle
			(center 0 0)
			(end 5.8166 0)
			(stroke
				(width 0.1)
				(type default)
			)
			(fill no)
			(layer "F.Fab")
		)
		(pad "" np_thru_hole circle
			(at 0 0)
			(size 10.0076 10.0076)
			(drill 10.0076)
			(layers "*.Cu" "*.Mask")
			(clearance 0.381)
			(thermal_gap 0.381)
		)
	)
	(footprint ""
		(layer "F.Cu")
		(at 46.093634 -391.089642)
		(property "Reference" "R4694"
			(at 0 0 0)
			(layer "F.SilkS")
			(hide yes)
			(effects
				(font
					(size 1.27 1.27)
				)
			)
		)
		(property "Value" ""
			(at 0 0 0)
			(layer "F.Fab")
			(effects
				(font
					(size 1.27 1.27)
				)
			)
		)
		(duplicate_pad_numbers_are_jumpers no)
		(fp_line
			(start -0.7874 -0.4064)
			(end 0.7874 -0.4064)
			(stroke
				(width 0.1524)
				(type default)
			)
			(layer "F.SilkS")
		)
		(fp_line
			(start -0.7874 0.4064)
			(end -0.7874 -0.4064)
			(stroke
				(width 0.1524)
				(type default)
			)
			(layer "F.SilkS")
		)
		(fp_line
			(start 0.7874 -0.4064)
			(end 0.7874 0.4064)
			(stroke
				(width 0.1524)
				(type default)
			)
			(layer "F.SilkS")
		)
		(fp_line
			(start 0.7874 0.4064)
			(end -0.7874 0.4064)
			(stroke
				(width 0.1524)
				(type default)
			)
			(layer "F.SilkS")
		)
		(fp_line
			(start -0.67945 -0.305054)
			(end -0.12065 -0.305054)
			(stroke
				(width 0.1)
				(type default)
			)
			(layer "F.Fab")
		)
		(fp_line
			(start -0.67945 0.3048)
			(end -0.67945 -0.305054)
			(stroke
				(width 0.1)
				(type default)
			)
			(layer "F.Fab")
		)
		(fp_line
			(start -0.12065 -0.305054)
			(end -0.12065 -0.2794)
			(stroke
				(width 0.1)
				(type default)
			)
			(layer "F.Fab")
		)
		(fp_line
			(start -0.12065 -0.2794)
			(end 0.12065 -0.2794)
			(stroke
				(width 0.1)
				(type default)
			)
			(layer "F.Fab")
		)
		(fp_line
			(start -0.12065 0.2794)
			(end -0.12065 0.3048)
			(stroke
				(width 0.1)
				(type default)
			)
			(layer "F.Fab")
		)
		(fp_line
			(start -0.12065 0.3048)
			(end -0.67945 0.3048)
			(stroke
				(width 0.1)
				(type default)
			)
			(layer "F.Fab")
		)
		(fp_line
			(start 0.120396 0.2794)
			(end -0.12065 0.2794)
			(stroke
				(width 0.1)
				(type default)
			)
			(layer "F.Fab")
		)
		(fp_line
			(start 0.120396 0.3048)
			(end 0.120396 0.2794)
			(stroke
				(width 0.1)
				(type default)
			)
			(layer "F.Fab")
		)
		(fp_line
			(start 0.12065 -0.3048)
			(end 0.67945 -0.3048)
			(stroke
				(width 0.1)
				(type default)
			)
			(layer "F.Fab")
		)
		(fp_line
			(start 0.12065 -0.2794)
			(end 0.12065 -0.3048)
			(stroke
				(width 0.1)
				(type default)
			)
			(layer "F.Fab")
		)
		(fp_line
			(start 0.67945 -0.3048)
			(end 0.67945 0.3048)
			(stroke
				(width 0.1)
				(type default)
			)
			(layer "F.Fab")
		)
		(fp_line
			(start 0.67945 0.3048)
			(end 0.120396 0.3048)
			(stroke
				(width 0.1)
				(type default)
			)
			(layer "F.Fab")
		)
		(pad "1" smd circle
			(at -0.40005 0)
			(size 0 0)
			(layers "F.Cu" "F.Mask" "F.Paste")
			(net "FM_P2E_BUF2_EQB1")
		)
		(pad "2" smd circle
			(at 0.40005 0)
			(size 0 0)
			(layers "F.Cu" "F.Mask" "F.Paste")
			(net "GND")
		)
	)
	(footprint ""
		(layer "F.Cu")
		(at 424.223942 -397.651478 180)
		(property "Reference" "R3430"
			(at 0 0 180)
			(layer "F.SilkS")
			(hide yes)
			(effects
				(font
					(size 1.27 1.27)
				)
			)
		)
		(property "Value" ""
			(at 0 0 180)
			(layer "F.Fab")
			(effects
				(font
					(size 1.27 1.27)
				)
			)
		)
		(duplicate_pad_numbers_are_jumpers no)
		(fp_line
			(start 0.7874 0.4064)
			(end -0.7874 0.4064)
			(stroke
				(width 0.1524)
				(type default)
			)
			(layer "F.SilkS")
		)
		(fp_line
			(start 0.7874 -0.4064)
			(end 0.7874 0.4064)
			(stroke
				(width 0.1524)
				(type default)
			)
			(layer "F.SilkS")
		)
		(fp_line
			(start -0.7874 0.4064)
			(end -0.7874 -0.4064)
			(stroke
				(width 0.1524)
				(type default)
			)
			(layer "F.SilkS")
		)
		(fp_line
			(start -0.7874 -0.4064)
			(end 0.7874 -0.4064)
			(stroke
				(width 0.1524)
				(type default)
			)
			(layer "F.SilkS")
		)
		(fp_line
			(start 0.67945 0.3048)
			(end 0.120396 0.3048)
			(stroke
				(width 0.1)
				(type default)
			)
			(layer "F.Fab")
		)
		(fp_line
			(start 0.67945 -0.3048)
			(end 0.67945 0.3048)
			(stroke
				(width 0.1)
				(type default)
			)
			(layer "F.Fab")
		)
		(fp_line
			(start 0.12065 -0.2794)
			(end 0.12065 -0.3048)
			(stroke
				(width 0.1)
				(type default)
			)
			(layer "F.Fab")
		)
		(fp_line
			(start 0.12065 -0.3048)
			(end 0.67945 -0.3048)
			(stroke
				(width 0.1)
				(type default)
			)
			(layer "F.Fab")
		)
		(fp_line
			(start 0.120396 0.3048)
			(end 0.120396 0.2794)
			(stroke
				(width 0.1)
				(type default)
			)
			(layer "F.Fab")
		)
		(fp_line
			(start 0.120396 0.2794)
			(end -0.12065 0.2794)
			(stroke
				(width 0.1)
				(type default)
			)
			(layer "F.Fab")
		)
		(fp_line
			(start -0.12065 0.3048)
			(end -0.67945 0.3048)
			(stroke
				(width 0.1)
				(type default)
			)
			(layer "F.Fab")
		)
		(fp_line
			(start -0.12065 0.2794)
			(end -0.12065 0.3048)
			(stroke
				(width 0.1)
				(type default)
			)
			(layer "F.Fab")
		)
		(fp_line
			(start -0.12065 -0.2794)
			(end 0.12065 -0.2794)
			(stroke
				(width 0.1)
				(type default)
			)
			(layer "F.Fab")
		)
		(fp_line
			(start -0.12065 -0.305054)
			(end -0.12065 -0.2794)
			(stroke
				(width 0.1)
				(type default)
			)
			(layer "F.Fab")
		)
		(fp_line
			(start -0.67945 0.3048)
			(end -0.67945 -0.305054)
			(stroke
				(width 0.1)
				(type default)
			)
			(layer "F.Fab")
		)
		(fp_line
			(start -0.67945 -0.305054)
			(end -0.12065 -0.305054)
			(stroke
				(width 0.1)
				(type default)
			)
			(layer "F.Fab")
		)
		(pad "1" smd circle
			(at -0.40005 0 180)
			(size 0 0)
			(layers "F.Cu" "F.Mask" "F.Paste")
			(net "GPU_FPGA_OVERT_N")
		)
		(pad "2" smd circle
			(at 0.40005 0 180)
			(size 0 0)
			(layers "F.Cu" "F.Mask" "F.Paste")
			(net "GND")
		)
	)
	(footprint ""
		(layer "F.Cu")
		(at 111.332772 -140.403326)
		(property "Reference" "R540"
			(at 0 0 0)
			(layer "F.SilkS")
			(hide yes)
			(effects
				(font
					(size 1.27 1.27)
				)
			)
		)
		(property "Value" ""
			(at 0 0 0)
			(layer "F.Fab")
			(effects
				(font
					(size 1.27 1.27)
				)
			)
		)
		(duplicate_pad_numbers_are_jumpers no)
		(fp_line
			(start -0.7874 -0.4064)
			(end 0.7874 -0.4064)
			(stroke
				(width 0.1524)
				(type default)
			)
			(layer "F.SilkS")
		)
		(fp_line
			(start -0.7874 0.4064)
			(end -0.7874 -0.4064)
			(stroke
				(width 0.1524)
				(type default)
			)
			(layer "F.SilkS")
		)
		(fp_line
			(start 0.7874 -0.4064)
			(end 0.7874 0.4064)
			(stroke
				(width 0.1524)
				(type default)
			)
			(layer "F.SilkS")
		)
		(fp_line
			(start 0.7874 0.4064)
			(end -0.7874 0.4064)
			(stroke
				(width 0.1524)
				(type default)
			)
			(layer "F.SilkS")
		)
		(fp_line
			(start -0.67945 -0.305054)
			(end -0.12065 -0.305054)
			(stroke
				(width 0.1)
				(type default)
			)
			(layer "F.Fab")
		)
		(fp_line
			(start -0.67945 0.3048)
			(end -0.67945 -0.305054)
			(stroke
				(width 0.1)
				(type default)
			)
			(layer "F.Fab")
		)
		(fp_line
			(start -0.12065 -0.305054)
			(end -0.12065 -0.2794)
			(stroke
				(width 0.1)
				(type default)
			)
			(layer "F.Fab")
		)
		(fp_line
			(start -0.12065 -0.2794)
			(end 0.12065 -0.2794)
			(stroke
				(width 0.1)
				(type default)
			)
			(layer "F.Fab")
		)
		(fp_line
			(start -0.12065 0.2794)
			(end -0.12065 0.3048)
			(stroke
				(width 0.1)
				(type default)
			)
			(layer "F.Fab")
		)
		(fp_line
			(start -0.12065 0.3048)
			(end -0.67945 0.3048)
			(stroke
				(width 0.1)
				(type default)
			)
			(layer "F.Fab")
		)
		(fp_line
			(start 0.120396 0.2794)
			(end -0.12065 0.2794)
			(stroke
				(width 0.1)
				(type default)
			)
			(layer "F.Fab")
		)
		(fp_line
			(start 0.120396 0.3048)
			(end 0.120396 0.2794)
			(stroke
				(width 0.1)
				(type default)
			)
			(layer "F.Fab")
		)
		(fp_line
			(start 0.12065 -0.3048)
			(end 0.67945 -0.3048)
			(stroke
				(width 0.1)
				(type default)
			)
			(layer "F.Fab")
		)
		(fp_line
			(start 0.12065 -0.2794)
			(end 0.12065 -0.3048)
			(stroke
				(width 0.1)
				(type default)
			)
			(layer "F.Fab")
		)
		(fp_line
			(start 0.67945 -0.3048)
			(end 0.67945 0.3048)
			(stroke
				(width 0.1)
				(type default)
			)
			(layer "F.Fab")
		)
		(fp_line
			(start 0.67945 0.3048)
			(end 0.120396 0.3048)
			(stroke
				(width 0.1)
				(type default)
			)
			(layer "F.Fab")
		)
		(pad "1" smd circle
			(at -0.40005 0)
			(size 0 0)
			(layers "F.Cu" "F.Mask" "F.Paste")
			(net "P3V3_AUX")
		)
		(pad "2" smd circle
			(at 0.40005 0)
			(size 0 0)
			(layers "F.Cu" "F.Mask" "F.Paste")
			(net "PCA9548_PCIE3_ADDR0")
		)
	)
	(footprint ""
		(layer "F.Cu")
		(at 124.33808 -106.238548 -90)
		(property "Reference" "R4048"
			(at 0 0 270)
			(layer "F.SilkS")
			(hide yes)
			(effects
				(font
					(size 1.27 1.27)
				)
			)
		)
		(property "Value" ""
			(at 0 0 270)
			(layer "F.Fab")
			(effects
				(font
					(size 1.27 1.27)
				)
			)
		)
		(duplicate_pad_numbers_are_jumpers no)
		(fp_line
			(start -0.7874 0.4064)
			(end -0.7874 -0.4064)
			(stroke
				(width 0.1524)
				(type default)
			)
			(layer "F.SilkS")
		)
		(fp_line
			(start 0.7874 0.4064)
			(end -0.7874 0.4064)
			(stroke
				(width 0.1524)
				(type default)
			)
			(layer "F.SilkS")
		)
		(fp_line
			(start -0.7874 -0.4064)
			(end 0.7874 -0.4064)
			(stroke
				(width 0.1524)
				(type default)
			)
			(layer "F.SilkS")
		)
		(fp_line
			(start 0.7874 -0.4064)
			(end 0.7874 0.4064)
			(stroke
				(width 0.1524)
				(type default)
			)
			(layer "F.SilkS")
		)
		(fp_line
			(start -0.67945 0.3048)
			(end -0.67945 -0.305054)
			(stroke
				(width 0.1)
				(type default)
			)
			(layer "F.Fab")
		)
		(fp_line
			(start -0.12065 0.3048)
			(end -0.67945 0.3048)
			(stroke
				(width 0.1)
				(type default)
			)
			(layer "F.Fab")
		)
		(fp_line
			(start 0.120396 0.3048)
			(end 0.120396 0.2794)
			(stroke
				(width 0.1)
				(type default)
			)
			(layer "F.Fab")
		)
		(fp_line
			(start 0.67945 0.3048)
			(end 0.120396 0.3048)
			(stroke
				(width 0.1)
				(type default)
			)
			(layer "F.Fab")
		)
		(fp_line
			(start -0.12065 0.2794)
			(end -0.12065 0.3048)
			(stroke
				(width 0.1)
				(type default)
			)
			(layer "F.Fab")
		)
		(fp_line
			(start 0.120396 0.2794)
			(end -0.12065 0.2794)
			(stroke
				(width 0.1)
				(type default)
			)
			(layer "F.Fab")
		)
		(fp_line
			(start -0.12065 -0.2794)
			(end 0.12065 -0.2794)
			(stroke
				(width 0.1)
				(type default)
			)
			(layer "F.Fab")
		)
		(fp_line
			(start 0.12065 -0.2794)
			(end 0.12065 -0.3048)
			(stroke
				(width 0.1)
				(type default)
			)
			(layer "F.Fab")
		)
		(fp_line
			(start 0.12065 -0.3048)
			(end 0.67945 -0.3048)
			(stroke
				(width 0.1)
				(type default)
			)
			(layer "F.Fab")
		)
		(fp_line
			(start 0.67945 -0.3048)
			(end 0.67945 0.3048)
			(stroke
				(width 0.1)
				(type default)
			)
			(layer "F.Fab")
		)
		(fp_line
			(start -0.67945 -0.305054)
			(end -0.12065 -0.305054)
			(stroke
				(width 0.1)
				(type default)
			)
			(layer "F.Fab")
		)
		(fp_line
			(start -0.12065 -0.305054)
			(end -0.12065 -0.2794)
			(stroke
				(width 0.1)
				(type default)
			)
			(layer "F.Fab")
		)
		(pad "1" smd circle
			(at -0.40005 0 270)
			(size 0 0)
			(layers "F.Cu" "F.Mask" "F.Paste")
			(net "RST_CPU1_DRAM_EF_PLD_LVT3_R_N")
		)
		(pad "2" smd circle
			(at 0.40005 0 270)
			(size 0 0)
			(layers "F.Cu" "F.Mask" "F.Paste")
			(net "RST_CPU1_DRAM_EF_PLD_LVT3_N")
		)
	)
	(footprint ""
		(layer "F.Cu")
		(at 120.10644 -414.274762 180)
		(property "Reference" "R4489"
			(at 0 0 180)
			(layer "F.SilkS")
			(hide yes)
			(effects
				(font
					(size 1.27 1.27)
				)
			)
		)
		(property "Value" ""
			(at 0 0 180)
			(layer "F.Fab")
			(effects
				(font
					(size 1.27 1.27)
				)
			)
		)
		(duplicate_pad_numbers_are_jumpers no)
		(fp_line
			(start 0.7874 0.4064)
			(end -0.7874 0.4064)
			(stroke
				(width 0.1524)
				(type default)
			)
			(layer "F.SilkS")
		)
		(fp_line
			(start 0.7874 -0.4064)
			(end 0.7874 0.4064)
			(stroke
				(width 0.1524)
				(type default)
			)
			(layer "F.SilkS")
		)
		(fp_line
			(start -0.7874 0.4064)
			(end -0.7874 -0.4064)
			(stroke
				(width 0.1524)
				(type default)
			)
			(layer "F.SilkS")
		)
		(fp_line
			(start -0.7874 -0.4064)
			(end 0.7874 -0.4064)
			(stroke
				(width 0.1524)
				(type default)
			)
			(layer "F.SilkS")
		)
		(fp_line
			(start 0.67945 0.3048)
			(end 0.120396 0.3048)
			(stroke
				(width 0.1)
				(type default)
			)
			(layer "F.Fab")
		)
		(fp_line
			(start 0.67945 -0.3048)
			(end 0.67945 0.3048)
			(stroke
				(width 0.1)
				(type default)
			)
			(layer "F.Fab")
		)
		(fp_line
			(start 0.12065 -0.2794)
			(end 0.12065 -0.3048)
			(stroke
				(width 0.1)
				(type default)
			)
			(layer "F.Fab")
		)
		(fp_line
			(start 0.12065 -0.3048)
			(end 0.67945 -0.3048)
			(stroke
				(width 0.1)
				(type default)
			)
			(layer "F.Fab")
		)
		(fp_line
			(start 0.120396 0.3048)
			(end 0.120396 0.2794)
			(stroke
				(width 0.1)
				(type default)
			)
			(layer "F.Fab")
		)
		(fp_line
			(start 0.120396 0.2794)
			(end -0.12065 0.2794)
			(stroke
				(width 0.1)
				(type default)
			)
			(layer "F.Fab")
		)
		(fp_line
			(start -0.12065 0.3048)
			(end -0.67945 0.3048)
			(stroke
				(width 0.1)
				(type default)
			)
			(layer "F.Fab")
		)
		(fp_line
			(start -0.12065 0.2794)
			(end -0.12065 0.3048)
			(stroke
				(width 0.1)
				(type default)
			)
			(layer "F.Fab")
		)
		(fp_line
			(start -0.12065 -0.2794)
			(end 0.12065 -0.2794)
			(stroke
				(width 0.1)
				(type default)
			)
			(layer "F.Fab")
		)
		(fp_line
			(start -0.12065 -0.305054)
			(end -0.12065 -0.2794)
			(stroke
				(width 0.1)
				(type default)
			)
			(layer "F.Fab")
		)
		(fp_line
			(start -0.67945 0.3048)
			(end -0.67945 -0.305054)
			(stroke
				(width 0.1)
				(type default)
			)
			(layer "F.Fab")
		)
		(fp_line
			(start -0.67945 -0.305054)
			(end -0.12065 -0.305054)
			(stroke
				(width 0.1)
				(type default)
			)
			(layer "F.Fab")
		)
		(pad "1" smd circle
			(at -0.40005 0 180)
			(size 0 0)
			(layers "F.Cu" "F.Mask" "F.Paste")
			(net "P3V3")
		)
		(pad "2" smd circle
			(at 0.40005 0 180)
			(size 0 0)
			(layers "F.Cu" "F.Mask" "F.Paste")
			(net "CLK_9ZXL045_SADR0")
		)
	)
)
